(kicad_pcb
	(version 20260206)
	(generator "pcbnew")
	(generator_version "10.0")
	(general
		(thickness 1.6)
		(legacy_teardrops no)
	)
	(paper "A4")
	(title_block
		(title "v1-chassis-manager — T6M_CM_d_v01_1031_1645.brd")
		(comment 1 "Open CloudServer (Microsoft) / footprints 934-943 of 2512")
	)
	(layers
		(0 "F.Cu" signal "TOP")
		(4 "In1.Cu" signal "GND1")
		(6 "In2.Cu" signal "IN1")
		(8 "In3.Cu" signal "VCC1")
		(10 "In4.Cu" signal "VCC2")
		(12 "In5.Cu" signal "GND2")
		(14 "In6.Cu" signal "IN2")
		(16 "In7.Cu" signal "IN3")
		(18 "In8.Cu" signal "GND3")
		(2 "B.Cu" signal "BOTTOM")
		(9 "F.Adhes" user "F.Adhesive")
		(11 "B.Adhes" user "B.Adhesive")
		(13 "F.Paste" user "Package Geometry/Pastemask Top")
		(15 "B.Paste" user "Package Geometry/Pastemask Bottom")
		(5 "F.SilkS" user "Ref Des/Silkscreen Top")
		(7 "B.SilkS" user "Ref Des/Silkscreen Bottom")
		(1 "F.Mask" user "Board Geometry/Soldermask Top")
		(3 "B.Mask" user "Board Geometry/Soldermask Bottom")
		(17 "Dwgs.User" user "User.Drawings")
		(19 "Cmts.User" user "User.Comments")
		(21 "Eco1.User" user "User.Eco1")
		(23 "Eco2.User" user "User.Eco2")
		(25 "Edge.Cuts" user "Board Geometry/Outline")
		(27 "Margin" user)
		(31 "F.CrtYd" user "Package Geometry/Place Bound Top")
		(29 "B.CrtYd" user "Package Geometry/Place Bound Bottom")
		(35 "F.Fab" user "Ref Des/Assembly Top")
		(33 "B.Fab" user "Ref Des/Assembly Bottom")
	)
	(footprint ""
		(layer "F.Cu")
		(at 65.734692 -107.316016 90)
		(property "Reference" "R1112"
			(at -1.118616 7.779258 90)
			(unlocked yes)
			(layer "F.SilkS")
			(effects
				(font
					(size 0.7874 0.5842)
					(thickness 0.1524)
				)
				(justify left)
			)
		)
		(property "Value" ""
			(at 0 0 90)
			(layer "F.Fab")
			(effects
				(font
					(size 1.27 1.27)
				)
			)
		)
		(duplicate_pad_numbers_are_jumpers no)
		(fp_line
			(start 0.7874 -0.4064)
			(end 0.7874 0.4064)
			(stroke
				(width 0.1524)
				(type default)
			)
			(layer "F.SilkS")
		)
		(fp_line
			(start -0.7874 -0.4064)
			(end 0.7874 -0.4064)
			(stroke
				(width 0.1524)
				(type default)
			)
			(layer "F.SilkS")
		)
		(fp_line
			(start 0.7874 0.4064)
			(end -0.7874 0.4064)
			(stroke
				(width 0.1524)
				(type default)
			)
			(layer "F.SilkS")
		)
		(fp_line
			(start -0.7874 0.4064)
			(end -0.7874 -0.4064)
			(stroke
				(width 0.1524)
				(type default)
			)
			(layer "F.SilkS")
		)
		(fp_poly
			(pts
				(xy -0.508 0.2794) (xy -0.508 0.2286) (xy -0.635 0.2286) (xy -0.635 -0.254) (xy -0.5334 -0.254)
				(xy -0.5334 -0.2794) (xy 0.5334 -0.2794) (xy 0.5334 -0.254) (xy 0.635 -0.254) (xy 0.635 0.254) (xy 0.5334 0.254)
				(xy 0.5334 0.2794)
			)
			(stroke
				(width 0)
				(type default)
			)
			(fill no)
			(layer "F.CrtYd")
		)
		(pad "1" smd rect
			(at 0.40005 0 90)
			(size 0.4572 0.508)
			(layers "F.Cu" "F.Mask" "F.Paste")
			(net "FM_CPLD_NODE1_P1V8_EN")
		)
		(pad "2" smd rect
			(at -0.40005 0 90)
			(size 0.4572 0.508)
			(layers "F.Cu" "F.Mask" "F.Paste")
			(net "P3V3_STB_NODE1")
		)
	)
	(footprint ""
		(layer "F.Cu")
		(at 17.96923 -43.589194 90)
		(property "Reference" "R789"
			(at -8.854186 -1.581404 90)
			(unlocked yes)
			(layer "F.SilkS")
			(effects
				(font
					(size 0.7874 0.5842)
					(thickness 0.1524)
				)
				(justify left)
			)
		)
		(property "Value" ""
			(at 0 0 90)
			(layer "F.Fab")
			(effects
				(font
					(size 1.27 1.27)
				)
			)
		)
		(duplicate_pad_numbers_are_jumpers no)
		(fp_line
			(start 0.7874 -0.4064)
			(end 0.7874 0.4064)
			(stroke
				(width 0.1524)
				(type default)
			)
			(layer "F.SilkS")
		)
		(fp_line
			(start -0.7874 -0.4064)
			(end 0.7874 -0.4064)
			(stroke
				(width 0.1524)
				(type default)
			)
			(layer "F.SilkS")
		)
		(fp_line
			(start 0.7874 0.4064)
			(end -0.7874 0.4064)
			(stroke
				(width 0.1524)
				(type default)
			)
			(layer "F.SilkS")
		)
		(fp_line
			(start -0.7874 0.4064)
			(end -0.7874 -0.4064)
			(stroke
				(width 0.1524)
				(type default)
			)
			(layer "F.SilkS")
		)
		(fp_poly
			(pts
				(xy -0.508 0.2794) (xy -0.508 0.2286) (xy -0.635 0.2286) (xy -0.635 -0.254) (xy -0.5334 -0.254)
				(xy -0.5334 -0.2794) (xy 0.5334 -0.2794) (xy 0.5334 -0.254) (xy 0.635 -0.254) (xy 0.635 0.254) (xy 0.5334 0.254)
				(xy 0.5334 0.2794)
			)
			(stroke
				(width 0)
				(type default)
			)
			(fill no)
			(layer "F.CrtYd")
		)
		(pad "1" smd rect
			(at 0.40005 0 90)
			(size 0.4572 0.508)
			(layers "F.Cu" "F.Mask" "F.Paste")
			(net "CRT_R_L")
		)
		(pad "2" smd rect
			(at -0.40005 0 90)
			(size 0.4572 0.508)
			(layers "F.Cu" "F.Mask" "F.Paste")
			(net "CRT_R")
		)
	)
	(footprint ""
		(layer "F.Cu")
		(at 11.246866 -97.354136 90)
		(property "Reference" "R1071"
			(at 3.306064 -0.6731 90)
			(unlocked yes)
			(layer "F.SilkS")
			(effects
				(font
					(size 0.7874 0.5842)
					(thickness 0.1524)
				)
				(justify left)
			)
		)
		(property "Value" ""
			(at 0 0 90)
			(layer "F.Fab")
			(effects
				(font
					(size 1.27 1.27)
				)
			)
		)
		(duplicate_pad_numbers_are_jumpers no)
		(fp_line
			(start 3.2258 -1.3462)
			(end 3.2258 1.3462)
			(stroke
				(width 0.1524)
				(type default)
			)
			(layer "F.SilkS")
		)
		(fp_line
			(start -3.2258 -1.3462)
			(end 3.2258 -1.3462)
			(stroke
				(width 0.1524)
				(type default)
			)
			(layer "F.SilkS")
		)
		(fp_line
			(start 3.2258 1.3462)
			(end -3.2258 1.3462)
			(stroke
				(width 0.1524)
				(type default)
			)
			(layer "F.SilkS")
		)
		(fp_line
			(start -3.2258 1.3462)
			(end -3.2258 -1.3462)
			(stroke
				(width 0.1524)
				(type default)
			)
			(layer "F.SilkS")
		)
		(fp_poly
			(pts
				(xy -2.5654 1.3462) (xy -2.5654 1.2192) (xy -3.0734 1.2192) (xy -3.0734 -1.2192) (xy -2.5654 -1.2192)
				(xy -2.5654 -1.3462) (xy 2.5654 -1.3462) (xy 2.5654 -1.2192) (xy 3.0734 -1.2192) (xy 3.0734 1.2192)
				(xy 2.5654 1.2192) (xy 2.5654 1.3462)
			)
			(stroke
				(width 0)
				(type default)
			)
			(fill no)
			(layer "F.CrtYd")
		)
		(pad "1" smd rect
			(at -2.350008 0 90)
			(size 1.4224 2.413)
			(layers "F.Cu" "F.Mask" "F.Paste")
			(net "P12V_DBG")
		)
		(pad "2" smd rect
			(at 2.350008 0 90)
			(size 1.4224 2.413)
			(layers "F.Cu" "F.Mask" "F.Paste")
			(net "P12V_PDB")
		)
	)
	(footprint ""
		(layer "F.Cu")
		(at 90.000074 -62.799976)
		(property "Reference" "H4"
			(at 1.533144 2.478532 0)
			(unlocked yes)
			(layer "F.SilkS")
			(effects
				(font
					(size 0.7874 0.5842)
					(thickness 0.1524)
				)
				(justify left)
			)
		)
		(property "Value" ""
			(at 0 0 0)
			(layer "F.Fab")
			(effects
				(font
					(size 1.27 1.27)
				)
			)
		)
		(duplicate_pad_numbers_are_jumpers no)
		(fp_circle
			(center 0 0)
			(end 2.3114 0)
			(stroke
				(width 0.1524)
				(type default)
			)
			(fill no)
			(layer "F.SilkS")
		)
		(fp_circle
			(center 0 0)
			(end 2.3114 0)
			(stroke
				(width 0.1524)
				(type default)
			)
			(fill no)
			(layer "B.SilkS")
		)
		(fp_poly
			(pts
				(arc
					(start 0 1.4986)
					(mid 0 -1.4986)
					(end 0 1.4986)
				)
			)
			(stroke
				(width 0)
				(type default)
			)
			(fill no)
			(layer "F.CrtYd")
		)
		(pad "" np_thru_hole circle
			(at 0 0)
			(size 2.9972 2.9972)
			(drill 2.9972)
			(layers "*.Cu" "*.Mask")
			(clearance 0.381)
			(thermal_gap 0.381)
		)
		(zone
			(layers "F.Cu" "B.Cu" "In1.Cu" "In2.Cu" "In3.Cu" "In4.Cu" "In5.Cu" "In6.Cu"
				"In7.Cu" "In8.Cu"
			)
			(hatch none 0.5)
			(connect_pads
				(clearance 0)
			)
			(min_thickness 0.25)
			(keepout
				(tracks not_allowed)
				(vias allowed)
				(pads allowed)
				(copperpour not_allowed)
				(footprints allowed)
			)
			(placement
				(enabled no)
				(sheetname "")
			)
			(fill
				(thermal_gap 0.5)
				(thermal_bridge_width 0.5)
				(island_removal_mode 0)
			)
			(polygon
				(pts
					(arc
						(start 90.000074 -60.793376)
						(mid 90.000074 -64.806576)
						(end 90.000074 -60.793376)
					)
				)
			)
		)
	)
	(footprint ""
		(layer "F.Cu")
		(at 169.817542 -131.721606 90)
		(property "Reference" "R661"
			(at -2.02057 -3.109976 90)
			(unlocked yes)
			(layer "F.SilkS")
			(effects
				(font
					(size 0.7874 0.5842)
					(thickness 0.1524)
				)
				(justify left)
			)
		)
		(property "Value" ""
			(at 0 0 90)
			(layer "F.Fab")
			(effects
				(font
					(size 1.27 1.27)
				)
			)
		)
		(duplicate_pad_numbers_are_jumpers no)
		(fp_line
			(start 0.7874 -0.4064)
			(end 0.7874 0.4064)
			(stroke
				(width 0.1524)
				(type default)
			)
			(layer "F.SilkS")
		)
		(fp_line
			(start -0.7874 -0.4064)
			(end 0.7874 -0.4064)
			(stroke
				(width 0.1524)
				(type default)
			)
			(layer "F.SilkS")
		)
		(fp_line
			(start 0.7874 0.4064)
			(end -0.7874 0.4064)
			(stroke
				(width 0.1524)
				(type default)
			)
			(layer "F.SilkS")
		)
		(fp_line
			(start -0.7874 0.4064)
			(end -0.7874 -0.4064)
			(stroke
				(width 0.1524)
				(type default)
			)
			(layer "F.SilkS")
		)
		(fp_poly
			(pts
				(xy -0.508 0.2794) (xy -0.508 0.2286) (xy -0.635 0.2286) (xy -0.635 -0.254) (xy -0.5334 -0.254)
				(xy -0.5334 -0.2794) (xy 0.5334 -0.2794) (xy 0.5334 -0.254) (xy 0.635 -0.254) (xy 0.635 0.254) (xy 0.5334 0.254)
				(xy 0.5334 0.2794)
			)
			(stroke
				(width 0)
				(type default)
			)
			(fill no)
			(layer "F.CrtYd")
		)
		(pad "1" smd rect
			(at 0.40005 0 90)
			(size 0.4572 0.508)
			(layers "F.Cu" "F.Mask" "F.Paste")
			(net "CPLD123_RSV3")
		)
		(pad "2" smd rect
			(at -0.40005 0 90)
			(size 0.4572 0.508)
			(layers "F.Cu" "F.Mask" "F.Paste")
			(net "CPLD1_RSV3")
		)
	)
	(footprint ""
		(layer "F.Cu")
		(at 86.642448 -107.9119)
		(property "Reference" "C42"
			(at -1.20015 -1.076452 0)
			(unlocked yes)
			(layer "F.SilkS")
			(effects
				(font
					(size 0.7874 0.5842)
					(thickness 0.1524)
				)
				(justify left)
			)
		)
		(property "Value" ""
			(at 0 0 0)
			(layer "F.Fab")
			(effects
				(font
					(size 1.27 1.27)
				)
			)
		)
		(duplicate_pad_numbers_are_jumpers no)
		(fp_line
			(start -0.7874 -0.4064)
			(end 0.7874 -0.4064)
			(stroke
				(width 0.1524)
				(type default)
			)
			(layer "F.SilkS")
		)
		(fp_line
			(start -0.7874 0.4064)
			(end -0.7874 -0.4064)
			(stroke
				(width 0.1524)
				(type default)
			)
			(layer "F.SilkS")
		)
		(fp_line
			(start 0 0.381)
			(end 0 -0.381)
			(stroke
				(width 0.1524)
				(type default)
			)
			(layer "F.SilkS")
		)
		(fp_line
			(start 0.7874 -0.4064)
			(end 0.7874 0.4064)
			(stroke
				(width 0.1524)
				(type default)
			)
			(layer "F.SilkS")
		)
		(fp_line
			(start 0.7874 0.4064)
			(end -0.7874 0.4064)
			(stroke
				(width 0.1524)
				(type default)
			)
			(layer "F.SilkS")
		)
		(fp_poly
			(pts
				(xy -0.5334 0.254) (xy -0.635 0.254) (xy -0.635 0.2286) (xy -0.635 -0.254) (xy -0.5334 -0.254) (xy -0.5334 -0.2794)
				(xy 0.5334 -0.2794) (xy 0.5334 -0.254) (xy 0.635 -0.254) (xy 0.635 0.254) (xy 0.5334 0.254) (xy 0.5334 0.2794)
				(xy -0.508 0.2794) (xy -0.5334 0.2794)
			)
			(stroke
				(width 0)
				(type default)
			)
			(fill no)
			(layer "F.CrtYd")
		)
		(pad "1" smd rect
			(at 0.40005 0)
			(size 0.4572 0.508)
			(layers "F.Cu" "F.Mask" "F.Paste")
			(net "P3V3_NODE1")
		)
		(pad "2" smd rect
			(at -0.40005 0)
			(size 0.4572 0.508)
			(layers "F.Cu" "F.Mask" "F.Paste")
			(net "GND")
		)
	)
	(footprint ""
		(layer "F.Cu")
		(at 25.000204 -182.79999)
		(property "Reference" "H8"
			(at 0 0 0)
			(layer "F.SilkS")
			(hide yes)
			(effects
				(font
					(size 1.27 1.27)
				)
			)
		)
		(property "Value" ""
			(at 0 0 0)
			(layer "F.Fab")
			(effects
				(font
					(size 1.27 1.27)
				)
			)
		)
		(duplicate_pad_numbers_are_jumpers no)
		(fp_poly
			(pts
				(arc
					(start 5.999734 5.050028)
					(mid 0 10.999933)
					(end -5.999734 5.050028)
				)
				(arc
					(start -5.999988 0.000254)
					(mid 0 -5.999988)
					(end 5.999988 0.000254)
				)
			)
			(stroke
				(width 0)
				(type default)
			)
			(fill no)
			(layer "B.CrtYd")
		)
		(fp_poly
			(pts
				(arc
					(start 5.999734 5.050028)
					(mid 0 10.999933)
					(end -5.999734 5.050028)
				)
				(arc
					(start -5.999988 0.000254)
					(mid 0 -5.999988)
					(end 5.999988 0.000254)
				)
			)
			(stroke
				(width 0)
				(type default)
			)
			(fill no)
			(layer "F.CrtYd")
		)
		(pad "" np_thru_hole circle
			(at 0 0)
			(size 3.6068 3.6068)
			(drill 3.6068)
			(layers "*.Cu" "*.Mask")
			(clearance 0.381)
			(thermal_gap 0.381)
		)
	)
	(footprint ""
		(layer "F.Cu")
		(at 68.940934 -2.944114 90)
		(property "Reference" "PR19"
			(at -2.74828 -2.869184 90)
			(unlocked yes)
			(layer "F.SilkS")
			(effects
				(font
					(size 0.7874 0.5842)
					(thickness 0.1524)
				)
				(justify left)
			)
		)
		(property "Value" ""
			(at 0 0 90)
			(layer "F.Fab")
			(effects
				(font
					(size 1.27 1.27)
				)
			)
		)
		(duplicate_pad_numbers_are_jumpers no)
		(fp_line
			(start 0.7874 -0.4064)
			(end 0.7874 0.4064)
			(stroke
				(width 0.1524)
				(type default)
			)
			(layer "F.SilkS")
		)
		(fp_line
			(start -0.7874 -0.4064)
			(end 0.7874 -0.4064)
			(stroke
				(width 0.1524)
				(type default)
			)
			(layer "F.SilkS")
		)
		(fp_line
			(start 0.7874 0.4064)
			(end -0.7874 0.4064)
			(stroke
				(width 0.1524)
				(type default)
			)
			(layer "F.SilkS")
		)
		(fp_line
			(start -0.7874 0.4064)
			(end -0.7874 -0.4064)
			(stroke
				(width 0.1524)
				(type default)
			)
			(layer "F.SilkS")
		)
		(fp_poly
			(pts
				(xy -0.508 0.2794) (xy -0.508 0.2286) (xy -0.635 0.2286) (xy -0.635 -0.254) (xy -0.5334 -0.254)
				(xy -0.5334 -0.2794) (xy 0.5334 -0.2794) (xy 0.5334 -0.254) (xy 0.635 -0.254) (xy 0.635 0.254) (xy 0.5334 0.254)
				(xy 0.5334 0.2794)
			)
			(stroke
				(width 0)
				(type default)
			)
			(fill no)
			(layer "F.CrtYd")
		)
		(pad "1" smd rect
			(at 0.40005 0 90)
			(size 0.4572 0.508)
			(layers "F.Cu" "F.Mask" "F.Paste")
			(net "PWRGD_NODE1_P3V3_PG")
		)
		(pad "2" smd rect
			(at -0.40005 0 90)
			(size 0.4572 0.508)
			(layers "F.Cu" "F.Mask" "F.Paste")
			(net "GND")
		)
	)
	(footprint ""
		(layer "F.Cu")
		(at 126.692152 -166.474902)
		(property "Reference" "C908"
			(at 0.07112 -4.415028 0)
			(unlocked yes)
			(layer "F.SilkS")
			(effects
				(font
					(size 0.7874 0.5842)
					(thickness 0.1524)
				)
			)
		)
		(property "Value" ""
			(at 0 0 0)
			(layer "F.Fab")
			(effects
				(font
					(size 1.27 1.27)
				)
			)
		)
		(duplicate_pad_numbers_are_jumpers no)
		(fp_line
			(start -1.2954 -0.5842)
			(end 1.2954 -0.5842)
			(stroke
				(width 0.1524)
				(type default)
			)
			(layer "F.SilkS")
		)
		(fp_line
			(start -1.2954 0.5842)
			(end -1.2954 -0.5842)
			(stroke
				(width 0.1524)
				(type default)
			)
			(layer "F.SilkS")
		)
		(fp_line
			(start 0 -0.5842)
			(end 0 0.5842)
			(stroke
				(width 0.1524)
				(type default)
			)
			(layer "F.SilkS")
		)
		(fp_line
			(start 1.2954 -0.5842)
			(end 1.2954 0.5842)
			(stroke
				(width 0.1524)
				(type default)
			)
			(layer "F.SilkS")
		)
		(fp_line
			(start 1.2954 0.5842)
			(end -1.2954 0.5842)
			(stroke
				(width 0.1524)
				(type default)
			)
			(layer "F.SilkS")
		)
		(fp_poly
			(pts
				(xy 0.8636 -0.4572) (xy 0.8636 -0.3556) (xy 1.143 -0.3556) (xy 1.143 0.3556) (xy 0.8636 0.3556)
				(xy 0.8636 0.4572) (xy -0.8636 0.4572) (xy -0.8636 0.3556) (xy -1.143 0.3556) (xy -1.143 -0.3556)
				(xy -0.8636 -0.3556) (xy -0.8636 -0.4572)
			)
			(stroke
				(width 0)
				(type default)
			)
			(fill no)
			(layer "F.CrtYd")
		)
		(fp_line
			(start -0.884936 -0.504952)
			(end 0.884936 -0.504952)
			(stroke
				(width 0.1)
				(type default)
			)
			(layer "F.Fab")
		)
		(fp_line
			(start -0.884936 0.504952)
			(end -0.884936 -0.504952)
			(stroke
				(width 0.1)
				(type default)
			)
			(layer "F.Fab")
		)
		(fp_line
			(start 0.884936 -0.504952)
			(end 0.884936 0.504952)
			(stroke
				(width 0.1)
				(type default)
			)
			(layer "F.Fab")
		)
		(fp_line
			(start 0.884936 0.504952)
			(end -0.884936 0.504952)
			(stroke
				(width 0.1)
				(type default)
			)
			(layer "F.Fab")
		)
		(pad "1" smd rect
			(at 0.7366 0 90)
			(size 0.7112 0.8128)
			(layers "F.Cu" "F.Mask" "F.Paste")
			(net "P3V3_NODE1")
		)
		(pad "2" smd rect
			(at -0.7366 0 90)
			(size 0.7112 0.8128)
			(layers "F.Cu" "F.Mask" "F.Paste")
			(net "GND")
		)
	)
	(footprint ""
		(layer "F.Cu")
		(at 156.586936 -171.496482 180)
		(property "Reference" "C914"
			(at 1.309116 -1.503934 0)
			(unlocked yes)
			(layer "F.SilkS")
			(effects
				(font
					(size 0.7874 0.5842)
					(thickness 0.1524)
				)
				(justify left)
			)
		)
		(property "Value" ""
			(at 0 0 180)
			(layer "F.Fab")
			(effects
				(font
					(size 1.27 1.27)
				)
			)
		)
		(duplicate_pad_numbers_are_jumpers no)
		(fp_line
			(start 0.7874 0.4064)
			(end -0.7874 0.4064)
			(stroke
				(width 0.1524)
				(type default)
			)
			(layer "F.SilkS")
		)
		(fp_line
			(start 0.7874 -0.4064)
			(end 0.7874 0.4064)
			(stroke
				(width 0.1524)
				(type default)
			)
			(layer "F.SilkS")
		)
		(fp_line
			(start 0 0.381)
			(end 0 -0.381)
			(stroke
				(width 0.1524)
				(type default)
			)
			(layer "F.SilkS")
		)
		(fp_line
			(start -0.7874 0.4064)
			(end -0.7874 -0.4064)
			(stroke
				(width 0.1524)
				(type default)
			)
			(layer "F.SilkS")
		)
		(fp_line
			(start -0.7874 -0.4064)
			(end 0.7874 -0.4064)
			(stroke
				(width 0.1524)
				(type default)
			)
			(layer "F.SilkS")
		)
		(fp_poly
			(pts
				(xy -0.5334 0.254) (xy -0.635 0.254) (xy -0.635 0.2286) (xy -0.635 -0.254) (xy -0.5334 -0.254) (xy -0.5334 -0.2794)
				(xy 0.5334 -0.2794) (xy 0.5334 -0.254) (xy 0.635 -0.254) (xy 0.635 0.254) (xy 0.5334 0.254) (xy 0.5334 0.2794)
				(xy -0.508 0.2794) (xy -0.5334 0.2794)
			)
			(stroke
				(width 0)
				(type default)
			)
			(fill no)
			(layer "F.CrtYd")
		)
		(pad "1" smd rect
			(at 0.40005 0 180)
			(size 0.4572 0.508)
			(layers "F.Cu" "F.Mask" "F.Paste")
			(net "GND")
		)
		(pad "2" smd rect
			(at -0.40005 0 180)
			(size 0.4572 0.508)
			(layers "F.Cu" "F.Mask" "F.Paste")
			(net "N54365623")
		)
	)
)
